# T6G (Grand Teton) — schematic netlist excerpt (pin names and nets, part order shuffled) for the footprints in the layout excerpt that follows; sources: Cadence DE-HDL packaged netlist, KiCad conversion of 04192023_DAF0TMB3IC0_F0TG_MB_C_brd_V02_OCP.brd

R3681  Q_RES  0 5% EMPTY  pkg 0402LF  page 257 : A = P3V3_AUX_ADC ; B = P3V3_AUX_ADC_MAM
PC6005  Q_CAP  0.01UF 25V 10% EMPTY  pkg C0402  page 209 : A = PVDD18_S5_P0_FB_RC ; B = PVDD18_S5_P0_RGND

(kicad_pcb
	(version 20260206)
	(generator "pcbnew")
	(generator_version "10.0")
	(general
		(thickness 1.6)
		(legacy_teardrops no)
	)
	(paper "A4")
	(title_block
		(title "04192023_DAF0TMB3IC0_F0TG_MB_C_brd_V02_OCP.brd")
		(comment 1 "Grand Teton / footprints 4730-4731 of 8354")
	)
	(layers
		(0 "F.Cu" signal "TOP")
		(4 "In1.Cu" signal "GND")
		(6 "In2.Cu" signal "IN1")
		(8 "In3.Cu" signal "GND1")
		(10 "In4.Cu" signal "IN2")
		(12 "In5.Cu" signal "GND2")
		(14 "In6.Cu" signal "IN3")
		(16 "In7.Cu" signal "GND3")
		(18 "In8.Cu" signal "VCC")
		(20 "In9.Cu" signal "VCC1")
		(22 "In10.Cu" signal "GND4")
		(24 "In11.Cu" signal "IN4")
		(26 "In12.Cu" signal "GND5")
		(28 "In13.Cu" signal "IN5")
		(30 "In14.Cu" signal "GND6")
		(32 "In15.Cu" signal "IN6")
		(34 "In16.Cu" signal "GND7")
		(2 "B.Cu" signal "BOTTOM")
		(9 "F.Adhes" user "F.Adhesive")
		(11 "B.Adhes" user "B.Adhesive")
		(13 "F.Paste" user "Package Geometry/Pastemask Top")
		(15 "B.Paste" user "Package Geometry/Pastemask Bottom")
		(5 "F.SilkS" user "Ref Des/Silkscreen Top")
		(7 "B.SilkS" user "Ref Des/Silkscreen Bottom")
		(1 "F.Mask" user "Board Geometry/Soldermask Top")
		(3 "B.Mask" user "Board Geometry/Soldermask Bottom")
		(17 "Dwgs.User" user "User.Drawings")
		(19 "Cmts.User" user "User.Comments")
		(21 "Eco1.User" user "User.Eco1")
		(23 "Eco2.User" user "User.Eco2")
		(25 "Edge.Cuts" user "Board Geometry/Outline")
		(27 "Margin" user)
		(31 "F.CrtYd" user "Package Geometry/Place Bound Top")
		(29 "B.CrtYd" user "Package Geometry/Place Bound Bottom")
		(35 "F.Fab" user "Ref Des/Assembly Top")
		(33 "B.Fab" user "Ref Des/Assembly Bottom")
	)
	(footprint ""
		(layer "F.Cu")
		(at 323.637148 -41.160954)
		(property "Reference" "R3681"
			(at 0 0 0)
			(layer "F.SilkS")
			(hide yes)
			(effects
				(font
					(size 1.27 1.27)
				)
			)
		)
		(property "Value" ""
			(at 0 0 0)
			(layer "F.Fab")
			(effects
				(font
					(size 1.27 1.27)
				)
			)
		)
		(duplicate_pad_numbers_are_jumpers no)
		(fp_line
			(start -0.7874 -0.4064)
			(end 0.7874 -0.4064)
			(stroke
				(width 0.1524)
				(type default)
			)
			(layer "F.SilkS")
		)
		(fp_line
			(start -0.7874 0.4064)
			(end -0.7874 -0.4064)
			(stroke
				(width 0.1524)
				(type default)
			)
			(layer "F.SilkS")
		)
		(fp_line
			(start 0.7874 -0.4064)
			(end 0.7874 0.4064)
			(stroke
				(width 0.1524)
				(type default)
			)
			(layer "F.SilkS")
		)
		(fp_line
			(start 0.7874 0.4064)
			(end -0.7874 0.4064)
			(stroke
				(width 0.1524)
				(type default)
			)
			(layer "F.SilkS")
		)
		(fp_line
			(start -0.67945 -0.305054)
			(end -0.12065 -0.305054)
			(stroke
				(width 0.1)
				(type default)
			)
			(layer "F.Fab")
		)
		(fp_line
			(start -0.67945 0.3048)
			(end -0.67945 -0.305054)
			(stroke
				(width 0.1)
				(type default)
			)
			(layer "F.Fab")
		)
		(fp_line
			(start -0.12065 -0.305054)
			(end -0.12065 -0.2794)
			(stroke
				(width 0.1)
				(type default)
			)
			(layer "F.Fab")
		)
		(fp_line
			(start -0.12065 -0.2794)
			(end 0.12065 -0.2794)
			(stroke
				(width 0.1)
				(type default)
			)
			(layer "F.Fab")
		)
		(fp_line
			(start -0.12065 0.2794)
			(end -0.12065 0.3048)
			(stroke
				(width 0.1)
				(type default)
			)
			(layer "F.Fab")
		)
		(fp_line
			(start -0.12065 0.3048)
			(end -0.67945 0.3048)
			(stroke
				(width 0.1)
				(type default)
			)
			(layer "F.Fab")
		)
		(fp_line
			(start 0.120396 0.2794)
			(end -0.12065 0.2794)
			(stroke
				(width 0.1)
				(type default)
			)
			(layer "F.Fab")
		)
		(fp_line
			(start 0.120396 0.3048)
			(end 0.120396 0.2794)
			(stroke
				(width 0.1)
				(type default)
			)
			(layer "F.Fab")
		)
		(fp_line
			(start 0.12065 -0.3048)
			(end 0.67945 -0.3048)
			(stroke
				(width 0.1)
				(type default)
			)
			(layer "F.Fab")
		)
		(fp_line
			(start 0.12065 -0.2794)
			(end 0.12065 -0.3048)
			(stroke
				(width 0.1)
				(type default)
			)
			(layer "F.Fab")
		)
		(fp_line
			(start 0.67945 -0.3048)
			(end 0.67945 0.3048)
			(stroke
				(width 0.1)
				(type default)
			)
			(layer "F.Fab")
		)
		(fp_line
			(start 0.67945 0.3048)
			(end 0.120396 0.3048)
			(stroke
				(width 0.1)
				(type default)
			)
			(layer "F.Fab")
		)
		(pad "1" smd rect
			(at -0.40005 0 180)
			(size 0.4572 0.508)
			(layers "F.Cu" "F.Mask" "F.Paste")
			(net "P3V3_AUX_ADC")
		)
		(pad "2" smd rect
			(at 0.40005 0 180)
			(size 0.4572 0.508)
			(layers "F.Cu" "F.Mask" "F.Paste")
			(net "P3V3_AUX_ADC_MAM")
		)
	)
	(footprint ""
		(layer "F.Cu")
		(at 328.868024 -140.245338)
		(property "Reference" "PC6005"
			(at 0 0 0)
			(layer "F.SilkS")
			(hide yes)
			(effects
				(font
					(size 1.27 1.27)
				)
			)
		)
		(property "Value" ""
			(at 0 0 0)
			(layer "F.Fab")
			(effects
				(font
					(size 1.27 1.27)
				)
			)
		)
		(duplicate_pad_numbers_are_jumpers no)
		(fp_line
			(start -0.7874 -0.4064)
			(end 0.7874 -0.4064)
			(stroke
				(width 0.1524)
				(type default)
			)
			(layer "F.SilkS")
		)
		(fp_line
			(start -0.7874 0.4064)
			(end -0.7874 -0.4064)
			(stroke
				(width 0.1524)
				(type default)
			)
			(layer "F.SilkS")
		)
		(fp_line
			(start 0.7874 -0.4064)
			(end 0.7874 0.4064)
			(stroke
				(width 0.1524)
				(type default)
			)
			(layer "F.SilkS")
		)
		(fp_line
			(start 0.7874 0.4064)
			(end -0.7874 0.4064)
			(stroke
				(width 0.1524)
				(type default)
			)
			(layer "F.SilkS")
		)
		(fp_line
			(start -0.67945 -0.305054)
			(end -0.12065 -0.305054)
			(stroke
				(width 0.1)
				(type default)
			)
			(layer "F.Fab")
		)
		(fp_line
			(start -0.67945 0.3048)
			(end -0.67945 -0.305054)
			(stroke
				(width 0.1)
				(type default)
			)
			(layer "F.Fab")
		)
		(fp_line
			(start -0.12065 -0.305054)
			(end -0.12065 -0.2794)
			(stroke
				(width 0.1)
				(type default)
			)
			(layer "F.Fab")
		)
		(fp_line
			(start -0.12065 -0.2794)
			(end 0.12065 -0.2794)
			(stroke
				(width 0.1)
				(type default)
			)
			(layer "F.Fab")
		)
		(fp_line
			(start -0.12065 0.2794)
			(end -0.12065 0.3048)
			(stroke
				(width 0.1)
				(type default)
			)
			(layer "F.Fab")
		)
		(fp_line
			(start -0.12065 0.3048)
			(end -0.67945 0.3048)
			(stroke
				(width 0.1)
				(type default)
			)
			(layer "F.Fab")
		)
		(fp_line
			(start 0.120396 0.2794)
			(end -0.12065 0.2794)
			(stroke
				(width 0.1)
				(type default)
			)
			(layer "F.Fab")
		)
		(fp_line
			(start 0.120396 0.3048)
			(end 0.120396 0.2794)
			(stroke
				(width 0.1)
				(type default)
			)
			(layer "F.Fab")
		)
		(fp_line
			(start 0.12065 -0.3048)
			(end 0.67945 -0.3048)
			(stroke
				(width 0.1)
				(type default)
			)
			(layer "F.Fab")
		)
		(fp_line
			(start 0.12065 -0.2794)
			(end 0.12065 -0.3048)
			(stroke
				(width 0.1)
				(type default)
			)
			(layer "F.Fab")
		)
		(fp_line
			(start 0.67945 -0.3048)
			(end 0.67945 0.3048)
			(stroke
				(width 0.1)
				(type default)
			)
			(layer "F.Fab")
		)
		(fp_line
			(start 0.67945 0.3048)
			(end 0.120396 0.3048)
			(stroke
				(width 0.1)
				(type default)
			)
			(layer "F.Fab")
		)
		(pad "1" smd circle
			(at -0.40005 0)
			(size 0 0)
			(layers "F.Cu" "F.Mask" "F.Paste")
			(net "PVDD18_S5_P0_FB_RC")
		)
		(pad "2" smd circle
			(at 0.40005 0)
			(size 0 0)
			(layers "F.Cu" "F.Mask" "F.Paste")
			(net "PVDD18_S5_P0_RGND")
		)
	)
)
